(kicad_pcb
	(version 20260206)
	(generator "pcbnew")
	(generator_version "10.0")
	(general
		(thickness 1.6)
		(legacy_teardrops no)
	)
	(paper "A4")
	(title_block
		(title "ptb — Lightning_PTB_BRD.brd")
		(comment 1 "Lightning (Wiwynn / Facebook NVMe JBOF) / footprints 24-29 of 61")
	)
	(layers
		(0 "F.Cu" signal "TOP")
		(4 "In1.Cu" signal "L2GND")
		(6 "In2.Cu" signal "L3VCC")
		(2 "B.Cu" signal "BOTTOM")
		(9 "F.Adhes" user "F.Adhesive")
		(11 "B.Adhes" user "B.Adhesive")
		(13 "F.Paste" user "Package Geometry/Pastemask Top")
		(15 "B.Paste" user "Package Geometry/Pastemask Bottom")
		(5 "F.SilkS" user "Ref Des/Silkscreen Top")
		(7 "B.SilkS" user "Ref Des/Silkscreen Bottom")
		(1 "F.Mask" user "Board Geometry/Soldermask Top")
		(3 "B.Mask" user "Board Geometry/Soldermask Bottom")
		(17 "Dwgs.User" user "User.Drawings")
		(19 "Cmts.User" user "User.Comments")
		(21 "Eco1.User" user "User.Eco1")
		(23 "Eco2.User" user "User.Eco2")
		(25 "Edge.Cuts" user "Board Geometry/Outline")
		(27 "Margin" user)
		(31 "F.CrtYd" user "Package Geometry/Place Bound Top")
		(29 "B.CrtYd" user "Package Geometry/Place Bound Bottom")
		(35 "F.Fab" user "Ref Des/Assembly Top")
		(33 "B.Fab" user "Ref Des/Assembly Bottom")
	)
	(footprint ""
		(layer "F.Cu")
		(at 155.650692 -103.082344)
		(property "Reference" "PR65"
			(at 0 0 0)
			(layer "F.SilkS")
			(hide yes)
			(effects
				(font
					(size 1.27 1.27)
				)
			)
		)
		(property "Value" "0R3J-0-U-GP"
			(at -0.0254 -2.5146 0)
			(unlocked yes)
			(layer "F.Fab")
			(hide yes)
			(effects
				(font
					(size 1.016 1.016)
					(thickness 0.1524)
				)
			)
		)
		(property "Device Type" "R603H22"
			(at -0.0254 -4.0386 0)
			(unlocked yes)
			(layer "F.Fab")
			(hide yes)
			(effects
				(font
					(size 1.016 1.016)
					(thickness 0.1524)
				)
			)
		)
		(duplicate_pad_numbers_are_jumpers no)
		(fp_line
			(start -0.4826 0)
			(end -0.2032 0)
			(stroke
				(width 0.2032)
				(type default)
			)
			(layer "F.SilkS")
		)
		(fp_line
			(start 0.2032 0)
			(end 0.4826 0)
			(stroke
				(width 0.2032)
				(type default)
			)
			(layer "F.SilkS")
		)
		(fp_rect
			(start -0.5842 1.3335)
			(end 0.5842 -1.3335)
			(stroke
				(width 0)
				(type default)
			)
			(fill no)
			(layer "F.CrtYd")
		)
		(fp_rect
			(start -0.5842 1.3335)
			(end 0.5842 -1.3335)
			(stroke
				(width 0)
				(type default)
			)
			(fill no)
			(layer "F.Fab")
		)
		(pad "1" smd custom
			(at 0 -0.762)
			(size 0.2159 0.2159)
			(layers "F.Cu" "F.Mask" "F.Paste")
			(net "P3V3")
			(options
				(clearance outline)
				(anchor circle)
			)
			(primitives
				(gr_poly
					(pts
						(arc
							(start -0.3302 -0.4318)
							(mid -0.402042 -0.402042)
							(end -0.4318 -0.3302)
						)
						(arc
							(start -0.4318 0.3302)
							(mid -0.402042 0.402042)
							(end -0.3302 0.4318)
						)
						(arc
							(start 0.3302 0.4318)
							(mid 0.402042 0.402042)
							(end 0.4318 0.3302)
						)
						(arc
							(start 0.4318 -0.3302)
							(mid 0.402042 -0.402042)
							(end 0.3302 -0.4318)
						)
					)
					(width 0)
					(fill yes)
				)
			)
		)
		(pad "2" smd custom
			(at 0 0.762)
			(size 0.2159 0.2159)
			(layers "F.Cu" "F.Mask" "F.Paste")
			(net "DETECTOR_C")
			(options
				(clearance outline)
				(anchor circle)
			)
			(primitives
				(gr_poly
					(pts
						(arc
							(start -0.3302 -0.4318)
							(mid -0.402042 -0.402042)
							(end -0.4318 -0.3302)
						)
						(arc
							(start -0.4318 0.3302)
							(mid -0.402042 0.402042)
							(end -0.3302 0.4318)
						)
						(arc
							(start 0.3302 0.4318)
							(mid 0.402042 0.402042)
							(end 0.4318 0.3302)
						)
						(arc
							(start 0.4318 -0.3302)
							(mid 0.402042 -0.402042)
							(end 0.3302 -0.4318)
						)
					)
					(width 0)
					(fill yes)
				)
			)
		)
	)
	(footprint ""
		(layer "F.Cu")
		(at 9.372092 -85.835744 90)
		(property "Reference" "R385"
			(at 0 0 90)
			(layer "F.SilkS")
			(hide yes)
			(effects
				(font
					(size 1.27 1.27)
				)
			)
		)
		(property "Value" "0R2J-2-GP"
			(at 0.064008 -3.993896 90)
			(unlocked yes)
			(layer "F.Fab")
			(hide yes)
			(effects
				(font
					(size 1.016 1.016)
					(thickness 0.1524)
				)
			)
		)
		(property "Device Type" "R402H16"
			(at 0.064008 -5.517896 90)
			(unlocked yes)
			(layer "F.Fab")
			(hide yes)
			(effects
				(font
					(size 1.016 1.016)
					(thickness 0.1524)
				)
			)
		)
		(duplicate_pad_numbers_are_jumpers no)
		(fp_line
			(start 0.508 -0.9398)
			(end -0.508 -0.9398)
			(stroke
				(width 0.1524)
				(type default)
			)
			(layer "F.SilkS")
		)
		(fp_line
			(start -0.508 -0.9398)
			(end -0.508 0.9398)
			(stroke
				(width 0.1524)
				(type default)
			)
			(layer "F.SilkS")
		)
		(fp_rect
			(start -0.508 0.9398)
			(end 0.508 -0.9398)
			(stroke
				(width 0)
				(type default)
			)
			(fill no)
			(layer "F.CrtYd")
		)
		(fp_rect
			(start -0.508 0.9398)
			(end 0.508 -0.9398)
			(stroke
				(width 0)
				(type default)
			)
			(fill no)
			(layer "F.Fab")
		)
		(pad "1" smd custom
			(at 0 -0.4445 90)
			(size 0.1397 0.1397)
			(layers "F.Cu" "F.Mask" "F.Paste")
			(net "PWM_EXP_B")
			(options
				(clearance outline)
				(anchor circle)
			)
			(primitives
				(gr_poly
					(pts
						(arc
							(start -0.1778 -0.2794)
							(mid -0.249642 -0.249642)
							(end -0.2794 -0.1778)
						)
						(arc
							(start -0.2794 0.1778)
							(mid -0.249642 0.249642)
							(end -0.1778 0.2794)
						)
						(arc
							(start 0.1778 0.2794)
							(mid 0.249642 0.249642)
							(end 0.2794 0.1778)
						)
						(arc
							(start 0.2794 -0.1778)
							(mid 0.249642 -0.249642)
							(end 0.1778 -0.2794)
						)
					)
					(width 0)
					(fill yes)
				)
			)
		)
		(pad "2" smd custom
			(at 0 0.4445 90)
			(size 0.1397 0.1397)
			(layers "F.Cu" "F.Mask" "F.Paste")
			(net "PWM_EXP_B_OUT")
			(options
				(clearance outline)
				(anchor circle)
			)
			(primitives
				(gr_poly
					(pts
						(arc
							(start -0.1778 -0.2794)
							(mid -0.249642 -0.249642)
							(end -0.2794 -0.1778)
						)
						(arc
							(start -0.2794 0.1778)
							(mid -0.249642 0.249642)
							(end -0.1778 0.2794)
						)
						(arc
							(start 0.1778 0.2794)
							(mid 0.249642 0.249642)
							(end 0.2794 0.1778)
						)
						(arc
							(start 0.2794 -0.1778)
							(mid 0.249642 -0.249642)
							(end 0.1778 -0.2794)
						)
					)
					(width 0)
					(fill yes)
				)
			)
		)
	)
	(footprint ""
		(layer "F.Cu")
		(at 17.218914 -92.751402 -90)
		(property "Reference" "R485"
			(at 0 0 270)
			(layer "F.SilkS")
			(hide yes)
			(effects
				(font
					(size 1.27 1.27)
				)
			)
		)
		(property "Value" "0R2J-2-GP"
			(at 0.064008 -3.993896 270)
			(unlocked yes)
			(layer "F.Fab")
			(hide yes)
			(effects
				(font
					(size 1.016 1.016)
					(thickness 0.1524)
				)
			)
		)
		(property "Device Type" "R402H16"
			(at 0.064008 -5.517896 270)
			(unlocked yes)
			(layer "F.Fab")
			(hide yes)
			(effects
				(font
					(size 1.016 1.016)
					(thickness 0.1524)
				)
			)
		)
		(duplicate_pad_numbers_are_jumpers no)
		(fp_line
			(start -0.508 -0.9398)
			(end -0.508 0.9398)
			(stroke
				(width 0.1524)
				(type default)
			)
			(layer "F.SilkS")
		)
		(fp_line
			(start 0.508 -0.9398)
			(end -0.508 -0.9398)
			(stroke
				(width 0.1524)
				(type default)
			)
			(layer "F.SilkS")
		)
		(fp_rect
			(start -0.508 0.9398)
			(end 0.508 -0.9398)
			(stroke
				(width 0)
				(type default)
			)
			(fill no)
			(layer "F.CrtYd")
		)
		(fp_rect
			(start -0.508 0.9398)
			(end 0.508 -0.9398)
			(stroke
				(width 0)
				(type default)
			)
			(fill no)
			(layer "F.Fab")
		)
		(pad "1" smd custom
			(at 0 -0.4445 270)
			(size 0.1397 0.1397)
			(layers "F.Cu" "F.Mask" "F.Paste")
			(net "I2C_C_BUF_SCL")
			(options
				(clearance outline)
				(anchor circle)
			)
			(primitives
				(gr_poly
					(pts
						(arc
							(start -0.1778 -0.2794)
							(mid -0.249642 -0.249642)
							(end -0.2794 -0.1778)
						)
						(arc
							(start -0.2794 0.1778)
							(mid -0.249642 0.249642)
							(end -0.1778 0.2794)
						)
						(arc
							(start 0.1778 0.2794)
							(mid 0.249642 0.249642)
							(end 0.2794 0.1778)
						)
						(arc
							(start 0.2794 -0.1778)
							(mid 0.249642 -0.249642)
							(end 0.1778 -0.2794)
						)
					)
					(width 0)
					(fill yes)
				)
			)
		)
		(pad "2" smd custom
			(at 0 0.4445 270)
			(size 0.1397 0.1397)
			(layers "F.Cu" "F.Mask" "F.Paste")
			(net "I2C_C_BUF_SCLIN")
			(options
				(clearance outline)
				(anchor circle)
			)
			(primitives
				(gr_poly
					(pts
						(arc
							(start -0.1778 -0.2794)
							(mid -0.249642 -0.249642)
							(end -0.2794 -0.1778)
						)
						(arc
							(start -0.2794 0.1778)
							(mid -0.249642 0.249642)
							(end -0.1778 0.2794)
						)
						(arc
							(start 0.1778 0.2794)
							(mid 0.249642 0.249642)
							(end 0.2794 0.1778)
						)
						(arc
							(start 0.2794 -0.1778)
							(mid 0.249642 -0.249642)
							(end 0.1778 -0.2794)
						)
					)
					(width 0)
					(fill yes)
				)
			)
		)
	)
	(footprint ""
		(layer "F.Cu")
		(at 133.223 -81.788 -90)
		(property "Reference" "R482"
			(at 0 0 270)
			(layer "F.SilkS")
			(hide yes)
			(effects
				(font
					(size 1.27 1.27)
				)
			)
		)
		(property "Value" "0R2J-2-GP"
			(at 0.064008 -3.993896 270)
			(unlocked yes)
			(layer "F.Fab")
			(hide yes)
			(effects
				(font
					(size 1.016 1.016)
					(thickness 0.1524)
				)
			)
		)
		(property "Device Type" "R402H16"
			(at 0.064008 -5.517896 270)
			(unlocked yes)
			(layer "F.Fab")
			(hide yes)
			(effects
				(font
					(size 1.016 1.016)
					(thickness 0.1524)
				)
			)
		)
		(duplicate_pad_numbers_are_jumpers no)
		(fp_line
			(start -0.508 -0.9398)
			(end -0.508 0.9398)
			(stroke
				(width 0.1524)
				(type default)
			)
			(layer "F.SilkS")
		)
		(fp_line
			(start 0.508 -0.9398)
			(end -0.508 -0.9398)
			(stroke
				(width 0.1524)
				(type default)
			)
			(layer "F.SilkS")
		)
		(fp_rect
			(start -0.508 0.9398)
			(end 0.508 -0.9398)
			(stroke
				(width 0)
				(type default)
			)
			(fill no)
			(layer "F.CrtYd")
		)
		(fp_rect
			(start -0.508 0.9398)
			(end 0.508 -0.9398)
			(stroke
				(width 0)
				(type default)
			)
			(fill no)
			(layer "F.Fab")
		)
		(pad "1" smd custom
			(at 0 -0.4445 270)
			(size 0.1397 0.1397)
			(layers "F.Cu" "F.Mask" "F.Paste")
			(net "TRAY PRESENT_OUT#_C")
			(options
				(clearance outline)
				(anchor circle)
			)
			(primitives
				(gr_poly
					(pts
						(arc
							(start -0.1778 -0.2794)
							(mid -0.249642 -0.249642)
							(end -0.2794 -0.1778)
						)
						(arc
							(start -0.2794 0.1778)
							(mid -0.249642 0.249642)
							(end -0.1778 0.2794)
						)
						(arc
							(start 0.1778 0.2794)
							(mid 0.249642 0.249642)
							(end 0.2794 0.1778)
						)
						(arc
							(start 0.2794 -0.1778)
							(mid 0.249642 -0.249642)
							(end 0.1778 -0.2794)
						)
					)
					(width 0)
					(fill yes)
				)
			)
		)
		(pad "2" smd custom
			(at 0 0.4445 270)
			(size 0.1397 0.1397)
			(layers "F.Cu" "F.Mask" "F.Paste")
			(net "TRAY_MOSFET_G")
			(options
				(clearance outline)
				(anchor circle)
			)
			(primitives
				(gr_poly
					(pts
						(arc
							(start -0.1778 -0.2794)
							(mid -0.249642 -0.249642)
							(end -0.2794 -0.1778)
						)
						(arc
							(start -0.2794 0.1778)
							(mid -0.249642 0.249642)
							(end -0.1778 0.2794)
						)
						(arc
							(start 0.1778 0.2794)
							(mid 0.249642 0.249642)
							(end 0.2794 0.1778)
						)
						(arc
							(start 0.2794 -0.1778)
							(mid 0.249642 -0.249642)
							(end 0.1778 -0.2794)
						)
					)
					(width 0)
					(fill yes)
				)
			)
		)
	)
	(footprint ""
		(layer "F.Cu")
		(at 17.233138 -94.990666 90)
		(property "Reference" "R481"
			(at 0 0 90)
			(layer "F.SilkS")
			(hide yes)
			(effects
				(font
					(size 1.27 1.27)
				)
			)
		)
		(property "Value" "0R2J-2-GP"
			(at 0.064008 -3.993896 90)
			(unlocked yes)
			(layer "F.Fab")
			(hide yes)
			(effects
				(font
					(size 1.016 1.016)
					(thickness 0.1524)
				)
			)
		)
		(property "Device Type" "R402H16"
			(at 0.064008 -5.517896 90)
			(unlocked yes)
			(layer "F.Fab")
			(hide yes)
			(effects
				(font
					(size 1.016 1.016)
					(thickness 0.1524)
				)
			)
		)
		(duplicate_pad_numbers_are_jumpers no)
		(fp_line
			(start 0.508 -0.9398)
			(end -0.508 -0.9398)
			(stroke
				(width 0.1524)
				(type default)
			)
			(layer "F.SilkS")
		)
		(fp_line
			(start -0.508 -0.9398)
			(end -0.508 0.9398)
			(stroke
				(width 0.1524)
				(type default)
			)
			(layer "F.SilkS")
		)
		(fp_rect
			(start -0.508 0.9398)
			(end 0.508 -0.9398)
			(stroke
				(width 0)
				(type default)
			)
			(fill no)
			(layer "F.CrtYd")
		)
		(fp_rect
			(start -0.508 0.9398)
			(end 0.508 -0.9398)
			(stroke
				(width 0)
				(type default)
			)
			(fill no)
			(layer "F.Fab")
		)
		(pad "1" smd custom
			(at 0 -0.4445 90)
			(size 0.1397 0.1397)
			(layers "F.Cu" "F.Mask" "F.Paste")
			(net "I2C_C_SDA")
			(options
				(clearance outline)
				(anchor circle)
			)
			(primitives
				(gr_poly
					(pts
						(arc
							(start -0.1778 -0.2794)
							(mid -0.249642 -0.249642)
							(end -0.2794 -0.1778)
						)
						(arc
							(start -0.2794 0.1778)
							(mid -0.249642 0.249642)
							(end -0.1778 0.2794)
						)
						(arc
							(start 0.1778 0.2794)
							(mid 0.249642 0.249642)
							(end 0.2794 0.1778)
						)
						(arc
							(start 0.2794 -0.1778)
							(mid 0.249642 -0.249642)
							(end 0.1778 -0.2794)
						)
					)
					(width 0)
					(fill yes)
				)
			)
		)
		(pad "2" smd custom
			(at 0 0.4445 90)
			(size 0.1397 0.1397)
			(layers "F.Cu" "F.Mask" "F.Paste")
			(net "I2C_C_BUF_SDA")
			(options
				(clearance outline)
				(anchor circle)
			)
			(primitives
				(gr_poly
					(pts
						(arc
							(start -0.1778 -0.2794)
							(mid -0.249642 -0.249642)
							(end -0.2794 -0.1778)
						)
						(arc
							(start -0.2794 0.1778)
							(mid -0.249642 0.249642)
							(end -0.1778 0.2794)
						)
						(arc
							(start 0.1778 0.2794)
							(mid 0.249642 0.249642)
							(end 0.2794 0.1778)
						)
						(arc
							(start 0.2794 -0.1778)
							(mid 0.249642 -0.249642)
							(end 0.1778 -0.2794)
						)
					)
					(width 0)
					(fill yes)
				)
			)
		)
	)
	(footprint ""
		(layer "F.Cu")
		(at 10.940288 -93.356938)
		(property "Reference" "R484"
			(at 0 0 0)
			(layer "F.SilkS")
			(hide yes)
			(effects
				(font
					(size 1.27 1.27)
				)
			)
		)
		(property "Value" "0R2J-2-GP"
			(at 0.064008 -3.993896 0)
			(unlocked yes)
			(layer "F.Fab")
			(hide yes)
			(effects
				(font
					(size 1.016 1.016)
					(thickness 0.1524)
				)
			)
		)
		(property "Device Type" "R402H16"
			(at 0.064008 -5.517896 0)
			(unlocked yes)
			(layer "F.Fab")
			(hide yes)
			(effects
				(font
					(size 1.016 1.016)
					(thickness 0.1524)
				)
			)
		)
		(duplicate_pad_numbers_are_jumpers no)
		(fp_line
			(start -0.508 -0.9398)
			(end -0.508 0.9398)
			(stroke
				(width 0.1524)
				(type default)
			)
			(layer "F.SilkS")
		)
		(fp_line
			(start 0.508 -0.9398)
			(end -0.508 -0.9398)
			(stroke
				(width 0.1524)
				(type default)
			)
			(layer "F.SilkS")
		)
		(fp_rect
			(start -0.508 0.9398)
			(end 0.508 -0.9398)
			(stroke
				(width 0)
				(type default)
			)
			(fill no)
			(layer "F.CrtYd")
		)
		(fp_rect
			(start -0.508 0.9398)
			(end 0.508 -0.9398)
			(stroke
				(width 0)
				(type default)
			)
			(fill no)
			(layer "F.Fab")
		)
		(pad "1" smd custom
			(at 0 -0.4445)
			(size 0.1397 0.1397)
			(layers "F.Cu" "F.Mask" "F.Paste")
			(net "I2C_C_SCL")
			(options
				(clearance outline)
				(anchor circle)
			)
			(primitives
				(gr_poly
					(pts
						(arc
							(start -0.1778 -0.2794)
							(mid -0.249642 -0.249642)
							(end -0.2794 -0.1778)
						)
						(arc
							(start -0.2794 0.1778)
							(mid -0.249642 0.249642)
							(end -0.1778 0.2794)
						)
						(arc
							(start 0.1778 0.2794)
							(mid 0.249642 0.249642)
							(end 0.2794 0.1778)
						)
						(arc
							(start 0.2794 -0.1778)
							(mid 0.249642 -0.249642)
							(end 0.1778 -0.2794)
						)
					)
					(width 0)
					(fill yes)
				)
			)
		)
		(pad "2" smd custom
			(at 0 0.4445)
			(size 0.1397 0.1397)
			(layers "F.Cu" "F.Mask" "F.Paste")
			(net "I2C_C_BUF_SCLOUT")
			(options
				(clearance outline)
				(anchor circle)
			)
			(primitives
				(gr_poly
					(pts
						(arc
							(start -0.1778 -0.2794)
							(mid -0.249642 -0.249642)
							(end -0.2794 -0.1778)
						)
						(arc
							(start -0.2794 0.1778)
							(mid -0.249642 0.249642)
							(end -0.1778 0.2794)
						)
						(arc
							(start 0.1778 0.2794)
							(mid 0.249642 0.249642)
							(end 0.2794 0.1778)
						)
						(arc
							(start 0.2794 -0.1778)
							(mid 0.249642 -0.249642)
							(end 0.1778 -0.2794)
						)
					)
					(width 0)
					(fill yes)
				)
			)
		)
	)
)
